(kicad_pcb
	(version 20260206)
	(generator "pcbnew")
	(generator_version "10.0")
	(general
		(thickness 1.6)
		(legacy_teardrops no)
	)
	(paper "A4")
	(title_block
		(title "04192023_DAF0TMB3IC0_F0TG_MB_C_brd_V02_OCP.brd")
		(comment 1 "Grand Teton / footprints 8143-8149 of 8354")
	)
	(layers
		(0 "F.Cu" signal "TOP")
		(4 "In1.Cu" signal "GND")
		(6 "In2.Cu" signal "IN1")
		(8 "In3.Cu" signal "GND1")
		(10 "In4.Cu" signal "IN2")
		(12 "In5.Cu" signal "GND2")
		(14 "In6.Cu" signal "IN3")
		(16 "In7.Cu" signal "GND3")
		(18 "In8.Cu" signal "VCC")
		(20 "In9.Cu" signal "VCC1")
		(22 "In10.Cu" signal "GND4")
		(24 "In11.Cu" signal "IN4")
		(26 "In12.Cu" signal "GND5")
		(28 "In13.Cu" signal "IN5")
		(30 "In14.Cu" signal "GND6")
		(32 "In15.Cu" signal "IN6")
		(34 "In16.Cu" signal "GND7")
		(2 "B.Cu" signal "BOTTOM")
		(9 "F.Adhes" user "F.Adhesive")
		(11 "B.Adhes" user "B.Adhesive")
		(13 "F.Paste" user "Package Geometry/Pastemask Top")
		(15 "B.Paste" user "Package Geometry/Pastemask Bottom")
		(5 "F.SilkS" user "Ref Des/Silkscreen Top")
		(7 "B.SilkS" user "Ref Des/Silkscreen Bottom")
		(1 "F.Mask" user "Board Geometry/Soldermask Top")
		(3 "B.Mask" user "Board Geometry/Soldermask Bottom")
		(17 "Dwgs.User" user "User.Drawings")
		(19 "Cmts.User" user "User.Comments")
		(21 "Eco1.User" user "User.Eco1")
		(23 "Eco2.User" user "User.Eco2")
		(25 "Edge.Cuts" user "Board Geometry/Outline")
		(27 "Margin" user)
		(31 "F.CrtYd" user "Package Geometry/Place Bound Top")
		(29 "B.CrtYd" user "Package Geometry/Place Bound Bottom")
		(35 "F.Fab" user "Ref Des/Assembly Top")
		(33 "B.Fab" user "Ref Des/Assembly Bottom")
	)
	(footprint ""
		(layer "B.Cu")
		(at 46.487334 -391.340848 -90)
		(property "Reference" "C221"
			(at 0 0 90)
			(layer "B.SilkS")
			(hide yes)
			(effects
				(font
					(size 1.27 1.27)
				)
				(justify mirror)
			)
		)
		(property "Value" ""
			(at 0 0 90)
			(layer "B.Fab")
			(effects
				(font
					(size 1.27 1.27)
				)
				(justify mirror)
			)
		)
		(duplicate_pad_numbers_are_jumpers no)
		(fp_line
			(start -0.7874 0.4064)
			(end 0.7874 0.4064)
			(stroke
				(width 0.1524)
				(type default)
			)
			(layer "B.SilkS")
		)
		(fp_line
			(start 0.7874 0.4064)
			(end 0.7874 -0.4064)
			(stroke
				(width 0.1524)
				(type default)
			)
			(layer "B.SilkS")
		)
		(fp_line
			(start -0.7874 -0.4064)
			(end -0.7874 0.4064)
			(stroke
				(width 0.1524)
				(type default)
			)
			(layer "B.SilkS")
		)
		(fp_line
			(start 0.7874 -0.4064)
			(end -0.7874 -0.4064)
			(stroke
				(width 0.1524)
				(type default)
			)
			(layer "B.SilkS")
		)
		(fp_line
			(start -0.67945 0.3048)
			(end -0.120396 0.3048)
			(stroke
				(width 0.1)
				(type default)
			)
			(layer "B.Fab")
		)
		(fp_line
			(start -0.120396 0.3048)
			(end -0.120396 0.2794)
			(stroke
				(width 0.1)
				(type default)
			)
			(layer "B.Fab")
		)
		(fp_line
			(start 0.12065 0.3048)
			(end 0.67945 0.3048)
			(stroke
				(width 0.1)
				(type default)
			)
			(layer "B.Fab")
		)
		(fp_line
			(start 0.67945 0.3048)
			(end 0.67945 -0.305054)
			(stroke
				(width 0.1)
				(type default)
			)
			(layer "B.Fab")
		)
		(fp_line
			(start -0.120396 0.2794)
			(end 0.12065 0.2794)
			(stroke
				(width 0.1)
				(type default)
			)
			(layer "B.Fab")
		)
		(fp_line
			(start 0.12065 0.2794)
			(end 0.12065 0.3048)
			(stroke
				(width 0.1)
				(type default)
			)
			(layer "B.Fab")
		)
		(fp_line
			(start -0.12065 -0.2794)
			(end -0.12065 -0.3048)
			(stroke
				(width 0.1)
				(type default)
			)
			(layer "B.Fab")
		)
		(fp_line
			(start 0.12065 -0.2794)
			(end -0.12065 -0.2794)
			(stroke
				(width 0.1)
				(type default)
			)
			(layer "B.Fab")
		)
		(fp_line
			(start -0.67945 -0.3048)
			(end -0.67945 0.3048)
			(stroke
				(width 0.1)
				(type default)
			)
			(layer "B.Fab")
		)
		(fp_line
			(start -0.12065 -0.3048)
			(end -0.67945 -0.3048)
			(stroke
				(width 0.1)
				(type default)
			)
			(layer "B.Fab")
		)
		(fp_line
			(start 0.12065 -0.305054)
			(end 0.12065 -0.2794)
			(stroke
				(width 0.1)
				(type default)
			)
			(layer "B.Fab")
		)
		(fp_line
			(start 0.67945 -0.305054)
			(end 0.12065 -0.305054)
			(stroke
				(width 0.1)
				(type default)
			)
			(layer "B.Fab")
		)
		(pad "1" smd circle
			(at 0.40005 0 90)
			(size 0 0)
			(layers "B.Cu" "B.Mask" "B.Paste")
			(net "P0V9_CPU1_RT0_2A")
		)
		(pad "2" smd circle
			(at -0.40005 0 90)
			(size 0 0)
			(layers "B.Cu" "B.Mask" "B.Paste")
			(net "GND")
		)
	)
	(footprint ""
		(layer "B.Cu")
		(at 233.807 -335.026 180)
		(property "Reference" "R1068"
			(at 0 0 0)
			(layer "B.SilkS")
			(hide yes)
			(effects
				(font
					(size 1.27 1.27)
				)
				(justify mirror)
			)
		)
		(property "Value" ""
			(at 0 0 0)
			(layer "B.Fab")
			(effects
				(font
					(size 1.27 1.27)
				)
				(justify mirror)
			)
		)
		(duplicate_pad_numbers_are_jumpers no)
		(fp_line
			(start 0.32512 0.175006)
			(end 0.32512 -0.175006)
			(stroke
				(width 0.1)
				(type default)
			)
			(layer "B.Fab")
		)
		(fp_line
			(start 0.32512 -0.175006)
			(end -0.32512 -0.175006)
			(stroke
				(width 0.1)
				(type default)
			)
			(layer "B.Fab")
		)
		(fp_line
			(start -0.32512 0.175006)
			(end 0.32512 0.175006)
			(stroke
				(width 0.1)
				(type default)
			)
			(layer "B.Fab")
		)
		(fp_line
			(start -0.32512 -0.175006)
			(end -0.32512 0.175006)
			(stroke
				(width 0.1)
				(type default)
			)
			(layer "B.Fab")
		)
		(pad "1" smd rect
			(at 0.2667 0)
			(size 0.3048 0.381)
			(layers "B.Cu" "B.Mask" "B.Paste")
			(net "SMB_RT_CPU0_P2_R_SDA")
		)
		(pad "2" smd rect
			(at -0.2667 0 180)
			(size 0.3048 0.381)
			(layers "B.Cu" "B.Mask" "B.Paste")
			(net "SMB_RT_CPU0_P2_R2_SDA")
		)
	)
	(footprint ""
		(layer "B.Cu")
		(at 208.461356 -388.692136)
		(property "Reference" "PR2519"
			(at 0 0 0)
			(layer "B.SilkS")
			(hide yes)
			(effects
				(font
					(size 1.27 1.27)
				)
				(justify mirror)
			)
		)
		(property "Value" ""
			(at 0 0 0)
			(layer "B.Fab")
			(effects
				(font
					(size 1.27 1.27)
				)
				(justify mirror)
			)
		)
		(duplicate_pad_numbers_are_jumpers no)
		(fp_line
			(start -0.7874 -0.4064)
			(end -0.7874 0.4064)
			(stroke
				(width 0.1524)
				(type default)
			)
			(layer "B.SilkS")
		)
		(fp_line
			(start -0.7874 0.4064)
			(end 0.7874 0.4064)
			(stroke
				(width 0.1524)
				(type default)
			)
			(layer "B.SilkS")
		)
		(fp_line
			(start 0.7874 -0.4064)
			(end -0.7874 -0.4064)
			(stroke
				(width 0.1524)
				(type default)
			)
			(layer "B.SilkS")
		)
		(fp_line
			(start 0.7874 0.4064)
			(end 0.7874 -0.4064)
			(stroke
				(width 0.1524)
				(type default)
			)
			(layer "B.SilkS")
		)
		(fp_line
			(start -0.67945 -0.3048)
			(end -0.67945 0.3048)
			(stroke
				(width 0.1)
				(type default)
			)
			(layer "B.Fab")
		)
		(fp_line
			(start -0.67945 0.3048)
			(end -0.120396 0.3048)
			(stroke
				(width 0.1)
				(type default)
			)
			(layer "B.Fab")
		)
		(fp_line
			(start -0.12065 -0.3048)
			(end -0.67945 -0.3048)
			(stroke
				(width 0.1)
				(type default)
			)
			(layer "B.Fab")
		)
		(fp_line
			(start -0.12065 -0.2794)
			(end -0.12065 -0.3048)
			(stroke
				(width 0.1)
				(type default)
			)
			(layer "B.Fab")
		)
		(fp_line
			(start -0.120396 0.2794)
			(end 0.12065 0.2794)
			(stroke
				(width 0.1)
				(type default)
			)
			(layer "B.Fab")
		)
		(fp_line
			(start -0.120396 0.3048)
			(end -0.120396 0.2794)
			(stroke
				(width 0.1)
				(type default)
			)
			(layer "B.Fab")
		)
		(fp_line
			(start 0.12065 -0.305054)
			(end 0.12065 -0.2794)
			(stroke
				(width 0.1)
				(type default)
			)
			(layer "B.Fab")
		)
		(fp_line
			(start 0.12065 -0.2794)
			(end -0.12065 -0.2794)
			(stroke
				(width 0.1)
				(type default)
			)
			(layer "B.Fab")
		)
		(fp_line
			(start 0.12065 0.2794)
			(end 0.12065 0.3048)
			(stroke
				(width 0.1)
				(type default)
			)
			(layer "B.Fab")
		)
		(fp_line
			(start 0.12065 0.3048)
			(end 0.67945 0.3048)
			(stroke
				(width 0.1)
				(type default)
			)
			(layer "B.Fab")
		)
		(fp_line
			(start 0.67945 -0.305054)
			(end 0.12065 -0.305054)
			(stroke
				(width 0.1)
				(type default)
			)
			(layer "B.Fab")
		)
		(fp_line
			(start 0.67945 0.3048)
			(end 0.67945 -0.305054)
			(stroke
				(width 0.1)
				(type default)
			)
			(layer "B.Fab")
		)
		(pad "1" smd circle
			(at 0.40005 0 180)
			(size 0 0)
			(layers "B.Cu" "B.Mask" "B.Paste")
			(net "P12V_HSC_ADC_N")
		)
		(pad "2" smd circle
			(at -0.40005 0 180)
			(size 0 0)
			(layers "B.Cu" "B.Mask" "B.Paste")
			(net "P12V_HSC_SENSE1_N")
		)
	)
	(footprint ""
		(layer "B.Cu")
		(at 413.123634 -193.99631)
		(property "Reference" "R96"
			(at 0 0 0)
			(layer "B.SilkS")
			(hide yes)
			(effects
				(font
					(size 1.27 1.27)
				)
				(justify mirror)
			)
		)
		(property "Value" ""
			(at 0 0 0)
			(layer "B.Fab")
			(effects
				(font
					(size 1.27 1.27)
				)
				(justify mirror)
			)
		)
		(duplicate_pad_numbers_are_jumpers no)
		(fp_line
			(start -0.7874 -0.4064)
			(end -0.7874 0.4064)
			(stroke
				(width 0.1524)
				(type default)
			)
			(layer "B.SilkS")
		)
		(fp_line
			(start -0.7874 0.4064)
			(end 0.7874 0.4064)
			(stroke
				(width 0.1524)
				(type default)
			)
			(layer "B.SilkS")
		)
		(fp_line
			(start 0.7874 -0.4064)
			(end -0.7874 -0.4064)
			(stroke
				(width 0.1524)
				(type default)
			)
			(layer "B.SilkS")
		)
		(fp_line
			(start 0.7874 0.4064)
			(end 0.7874 -0.4064)
			(stroke
				(width 0.1524)
				(type default)
			)
			(layer "B.SilkS")
		)
		(fp_line
			(start -0.67945 -0.3048)
			(end -0.67945 0.3048)
			(stroke
				(width 0.1)
				(type default)
			)
			(layer "B.Fab")
		)
		(fp_line
			(start -0.67945 0.3048)
			(end -0.120396 0.3048)
			(stroke
				(width 0.1)
				(type default)
			)
			(layer "B.Fab")
		)
		(fp_line
			(start -0.12065 -0.3048)
			(end -0.67945 -0.3048)
			(stroke
				(width 0.1)
				(type default)
			)
			(layer "B.Fab")
		)
		(fp_line
			(start -0.12065 -0.2794)
			(end -0.12065 -0.3048)
			(stroke
				(width 0.1)
				(type default)
			)
			(layer "B.Fab")
		)
		(fp_line
			(start -0.120396 0.2794)
			(end 0.12065 0.2794)
			(stroke
				(width 0.1)
				(type default)
			)
			(layer "B.Fab")
		)
		(fp_line
			(start -0.120396 0.3048)
			(end -0.120396 0.2794)
			(stroke
				(width 0.1)
				(type default)
			)
			(layer "B.Fab")
		)
		(fp_line
			(start 0.12065 -0.305054)
			(end 0.12065 -0.2794)
			(stroke
				(width 0.1)
				(type default)
			)
			(layer "B.Fab")
		)
		(fp_line
			(start 0.12065 -0.2794)
			(end -0.12065 -0.2794)
			(stroke
				(width 0.1)
				(type default)
			)
			(layer "B.Fab")
		)
		(fp_line
			(start 0.12065 0.2794)
			(end 0.12065 0.3048)
			(stroke
				(width 0.1)
				(type default)
			)
			(layer "B.Fab")
		)
		(fp_line
			(start 0.12065 0.3048)
			(end 0.67945 0.3048)
			(stroke
				(width 0.1)
				(type default)
			)
			(layer "B.Fab")
		)
		(fp_line
			(start 0.67945 -0.305054)
			(end 0.12065 -0.305054)
			(stroke
				(width 0.1)
				(type default)
			)
			(layer "B.Fab")
		)
		(fp_line
			(start 0.67945 0.3048)
			(end 0.67945 -0.305054)
			(stroke
				(width 0.1)
				(type default)
			)
			(layer "B.Fab")
		)
		(pad "1" smd circle
			(at 0.40005 0 180)
			(size 0 0)
			(layers "B.Cu" "B.Mask" "B.Paste")
			(net "P3V3")
		)
		(pad "2" smd circle
			(at -0.40005 0 180)
			(size 0 0)
			(layers "B.Cu" "B.Mask" "B.Paste")
			(net "PWRGD_CHG_CPU0_DIMM0")
		)
	)
	(footprint ""
		(layer "B.Cu")
		(at 111.214154 -190.870332 90)
		(property "Reference" "PC305_4"
			(at 0 0 90)
			(layer "B.SilkS")
			(hide yes)
			(effects
				(font
					(size 1.27 1.27)
				)
				(justify mirror)
			)
		)
		(property "Value" ""
			(at 0 0 90)
			(layer "B.Fab")
			(effects
				(font
					(size 1.27 1.27)
				)
				(justify mirror)
			)
		)
		(duplicate_pad_numbers_are_jumpers no)
		(fp_line
			(start 1.524 -0.762)
			(end -1.524 -0.762)
			(stroke
				(width 0.1524)
				(type default)
			)
			(layer "B.SilkS")
		)
		(fp_line
			(start -1.524 -0.762)
			(end -1.524 0.762)
			(stroke
				(width 0.1524)
				(type default)
			)
			(layer "B.SilkS")
		)
		(fp_line
			(start 1.524 0.762)
			(end 1.524 -0.762)
			(stroke
				(width 0.1524)
				(type default)
			)
			(layer "B.SilkS")
		)
		(fp_line
			(start -1.524 0.762)
			(end 1.524 0.762)
			(stroke
				(width 0.1524)
				(type default)
			)
			(layer "B.SilkS")
		)
		(fp_line
			(start 1.1049 -0.724916)
			(end 1.1049 0.724916)
			(stroke
				(width 0.1)
				(type default)
			)
			(layer "B.Fab")
		)
		(fp_line
			(start -1.1049 -0.724916)
			(end 1.1049 -0.724916)
			(stroke
				(width 0.1)
				(type default)
			)
			(layer "B.Fab")
		)
		(fp_line
			(start 1.1049 0.724916)
			(end -1.1049 0.724916)
			(stroke
				(width 0.1)
				(type default)
			)
			(layer "B.Fab")
		)
		(fp_line
			(start -1.1049 0.724916)
			(end -1.1049 -0.724916)
			(stroke
				(width 0.1)
				(type default)
			)
			(layer "B.Fab")
		)
		(pad "1" smd rect
			(at 0.889 0 90)
			(size 1.016 1.27)
			(layers "B.Cu" "B.Mask" "B.Paste")
			(net "PVDDCR_CPU0_P1")
		)
		(pad "2" smd rect
			(at -0.889 0 90)
			(size 1.016 1.27)
			(layers "B.Cu" "B.Mask" "B.Paste")
			(net "GND")
		)
	)
	(footprint ""
		(layer "B.Cu")
		(at 240.919 -236.855 90)
		(property "Reference" "C25"
			(at 0 0 90)
			(layer "B.SilkS")
			(hide yes)
			(effects
				(font
					(size 1.27 1.27)
				)
				(justify mirror)
			)
		)
		(property "Value" ""
			(at 0 0 90)
			(layer "B.Fab")
			(effects
				(font
					(size 1.27 1.27)
				)
				(justify mirror)
			)
		)
		(duplicate_pad_numbers_are_jumpers no)
		(fp_line
			(start 0.7874 -0.4064)
			(end -0.7874 -0.4064)
			(stroke
				(width 0.1524)
				(type default)
			)
			(layer "B.SilkS")
		)
		(fp_line
			(start -0.7874 -0.4064)
			(end -0.7874 0.4064)
			(stroke
				(width 0.1524)
				(type default)
			)
			(layer "B.SilkS")
		)
		(fp_line
			(start 0.7874 0.4064)
			(end 0.7874 -0.4064)
			(stroke
				(width 0.1524)
				(type default)
			)
			(layer "B.SilkS")
		)
		(fp_line
			(start -0.7874 0.4064)
			(end 0.7874 0.4064)
			(stroke
				(width 0.1524)
				(type default)
			)
			(layer "B.SilkS")
		)
		(fp_line
			(start 0.67945 -0.305054)
			(end 0.12065 -0.305054)
			(stroke
				(width 0.1)
				(type default)
			)
			(layer "B.Fab")
		)
		(fp_line
			(start 0.12065 -0.305054)
			(end 0.12065 -0.2794)
			(stroke
				(width 0.1)
				(type default)
			)
			(layer "B.Fab")
		)
		(fp_line
			(start -0.12065 -0.3048)
			(end -0.67945 -0.3048)
			(stroke
				(width 0.1)
				(type default)
			)
			(layer "B.Fab")
		)
		(fp_line
			(start -0.67945 -0.3048)
			(end -0.67945 0.3048)
			(stroke
				(width 0.1)
				(type default)
			)
			(layer "B.Fab")
		)
		(fp_line
			(start 0.12065 -0.2794)
			(end -0.12065 -0.2794)
			(stroke
				(width 0.1)
				(type default)
			)
			(layer "B.Fab")
		)
		(fp_line
			(start -0.12065 -0.2794)
			(end -0.12065 -0.3048)
			(stroke
				(width 0.1)
				(type default)
			)
			(layer "B.Fab")
		)
		(fp_line
			(start 0.12065 0.2794)
			(end 0.12065 0.3048)
			(stroke
				(width 0.1)
				(type default)
			)
			(layer "B.Fab")
		)
		(fp_line
			(start -0.120396 0.2794)
			(end 0.12065 0.2794)
			(stroke
				(width 0.1)
				(type default)
			)
			(layer "B.Fab")
		)
		(fp_line
			(start 0.67945 0.3048)
			(end 0.67945 -0.305054)
			(stroke
				(width 0.1)
				(type default)
			)
			(layer "B.Fab")
		)
		(fp_line
			(start 0.12065 0.3048)
			(end 0.67945 0.3048)
			(stroke
				(width 0.1)
				(type default)
			)
			(layer "B.Fab")
		)
		(fp_line
			(start -0.120396 0.3048)
			(end -0.120396 0.2794)
			(stroke
				(width 0.1)
				(type default)
			)
			(layer "B.Fab")
		)
		(fp_line
			(start -0.67945 0.3048)
			(end -0.120396 0.3048)
			(stroke
				(width 0.1)
				(type default)
			)
			(layer "B.Fab")
		)
		(pad "1" smd circle
			(at 0.40005 0 270)
			(size 0 0)
			(layers "B.Cu" "B.Mask" "B.Paste")
			(net "P3V3_AUX")
		)
		(pad "2" smd circle
			(at -0.40005 0 270)
			(size 0 0)
			(layers "B.Cu" "B.Mask" "B.Paste")
			(net "GND")
		)
	)
	(footprint ""
		(layer "B.Cu")
		(at 273.111214 -347.77553 -90)
		(property "Reference" "PR107"
			(at 0 0 90)
			(layer "B.SilkS")
			(hide yes)
			(effects
				(font
					(size 1.27 1.27)
				)
				(justify mirror)
			)
		)
		(property "Value" ""
			(at 0 0 90)
			(layer "B.Fab")
			(effects
				(font
					(size 1.27 1.27)
				)
				(justify mirror)
			)
		)
		(duplicate_pad_numbers_are_jumpers no)
		(fp_line
			(start -0.7874 0.4064)
			(end 0.7874 0.4064)
			(stroke
				(width 0.1524)
				(type default)
			)
			(layer "B.SilkS")
		)
		(fp_line
			(start 0.7874 0.4064)
			(end 0.7874 -0.4064)
			(stroke
				(width 0.1524)
				(type default)
			)
			(layer "B.SilkS")
		)
		(fp_line
			(start -0.7874 -0.4064)
			(end -0.7874 0.4064)
			(stroke
				(width 0.1524)
				(type default)
			)
			(layer "B.SilkS")
		)
		(fp_line
			(start 0.7874 -0.4064)
			(end -0.7874 -0.4064)
			(stroke
				(width 0.1524)
				(type default)
			)
			(layer "B.SilkS")
		)
		(fp_line
			(start -0.67945 0.3048)
			(end -0.120396 0.3048)
			(stroke
				(width 0.1)
				(type default)
			)
			(layer "B.Fab")
		)
		(fp_line
			(start -0.120396 0.3048)
			(end -0.120396 0.2794)
			(stroke
				(width 0.1)
				(type default)
			)
			(layer "B.Fab")
		)
		(fp_line
			(start 0.12065 0.3048)
			(end 0.67945 0.3048)
			(stroke
				(width 0.1)
				(type default)
			)
			(layer "B.Fab")
		)
		(fp_line
			(start 0.67945 0.3048)
			(end 0.67945 -0.305054)
			(stroke
				(width 0.1)
				(type default)
			)
			(layer "B.Fab")
		)
		(fp_line
			(start -0.120396 0.2794)
			(end 0.12065 0.2794)
			(stroke
				(width 0.1)
				(type default)
			)
			(layer "B.Fab")
		)
		(fp_line
			(start 0.12065 0.2794)
			(end 0.12065 0.3048)
			(stroke
				(width 0.1)
				(type default)
			)
			(layer "B.Fab")
		)
		(fp_line
			(start -0.12065 -0.2794)
			(end -0.12065 -0.3048)
			(stroke
				(width 0.1)
				(type default)
			)
			(layer "B.Fab")
		)
		(fp_line
			(start 0.12065 -0.2794)
			(end -0.12065 -0.2794)
			(stroke
				(width 0.1)
				(type default)
			)
			(layer "B.Fab")
		)
		(fp_line
			(start -0.67945 -0.3048)
			(end -0.67945 0.3048)
			(stroke
				(width 0.1)
				(type default)
			)
			(layer "B.Fab")
		)
		(fp_line
			(start -0.12065 -0.3048)
			(end -0.67945 -0.3048)
			(stroke
				(width 0.1)
				(type default)
			)
			(layer "B.Fab")
		)
		(fp_line
			(start 0.12065 -0.305054)
			(end 0.12065 -0.2794)
			(stroke
				(width 0.1)
				(type default)
			)
			(layer "B.Fab")
		)
		(fp_line
			(start 0.67945 -0.305054)
			(end 0.12065 -0.305054)
			(stroke
				(width 0.1)
				(type default)
			)
			(layer "B.Fab")
		)
		(pad "1" smd circle
			(at 0.40005 0 90)
			(size 0 0)
			(layers "B.Cu" "B.Mask" "B.Paste")
			(net "PVDDCR_CPU1_P0_PVCC")
		)
		(pad "2" smd circle
			(at -0.40005 0 90)
			(size 0 0)
			(layers "B.Cu" "B.Mask" "B.Paste")
			(net "PVDDIO_P0_VCC4")
		)
	)
)
